(kicad_pcb
	(version 20260206)
	(generator "pcbnew")
	(generator_version "10.0")
	(general
		(thickness 1.6)
		(legacy_teardrops no)
	)
	(paper "A4")
	(title_block
		(title "pdpb — Lightning_PDPB_BRD.brd")
		(comment 1 "Lightning (Wiwynn / Facebook NVMe JBOF) / footprints 883-888 of 1140")
	)
	(layers
		(0 "F.Cu" signal "TOP")
		(4 "In1.Cu" signal "L2GND")
		(6 "In2.Cu" signal "L3")
		(8 "In3.Cu" signal "L4VCC")
		(10 "In4.Cu" signal "L5VCC")
		(12 "In5.Cu" signal "L6")
		(14 "In6.Cu" signal "L7GND")
		(2 "B.Cu" signal "BOTTOM")
		(9 "F.Adhes" user "F.Adhesive")
		(11 "B.Adhes" user "B.Adhesive")
		(13 "F.Paste" user "Package Geometry/Pastemask Top")
		(15 "B.Paste" user "Package Geometry/Pastemask Bottom")
		(5 "F.SilkS" user "Ref Des/Silkscreen Top")
		(7 "B.SilkS" user "Ref Des/Silkscreen Bottom")
		(1 "F.Mask" user "Board Geometry/Soldermask Top")
		(3 "B.Mask" user "Board Geometry/Soldermask Bottom")
		(17 "Dwgs.User" user "User.Drawings")
		(19 "Cmts.User" user "User.Comments")
		(21 "Eco1.User" user "User.Eco1")
		(23 "Eco2.User" user "User.Eco2")
		(25 "Edge.Cuts" user "Board Geometry/Outline")
		(27 "Margin" user)
		(31 "F.CrtYd" user "Package Geometry/Place Bound Top")
		(29 "B.CrtYd" user "Package Geometry/Place Bound Bottom")
		(35 "F.Fab" user "Ref Des/Assembly Top")
		(33 "B.Fab" user "Ref Des/Assembly Bottom")
	)
	(footprint ""
		(layer "F.Cu")
		(at 29.9466 -290.6522)
		(property "Reference" "SR1105"
			(at 0 0 0)
			(layer "F.SilkS")
			(hide yes)
			(effects
				(font
					(size 1.27 1.27)
				)
			)
		)
		(property "Value" "4K7R2F-GP"
			(at 0.064008 -3.993896 0)
			(unlocked yes)
			(layer "F.Fab")
			(hide yes)
			(effects
				(font
					(size 1.016 1.016)
					(thickness 0.1524)
				)
			)
		)
		(property "Device Type" "R402H16"
			(at 0.064008 -5.517896 0)
			(unlocked yes)
			(layer "F.Fab")
			(hide yes)
			(effects
				(font
					(size 1.016 1.016)
					(thickness 0.1524)
				)
			)
		)
		(duplicate_pad_numbers_are_jumpers no)
		(fp_line
			(start -0.508 -0.9398)
			(end -0.508 0.9398)
			(stroke
				(width 0.1524)
				(type default)
			)
			(layer "F.SilkS")
		)
		(fp_line
			(start 0.508 -0.9398)
			(end -0.508 -0.9398)
			(stroke
				(width 0.1524)
				(type default)
			)
			(layer "F.SilkS")
		)
		(fp_rect
			(start -0.508 0.9398)
			(end 0.508 -0.9398)
			(stroke
				(width 0)
				(type default)
			)
			(fill no)
			(layer "F.CrtYd")
		)
		(fp_rect
			(start -0.508 0.9398)
			(end 0.508 -0.9398)
			(stroke
				(width 0)
				(type default)
			)
			(fill no)
			(layer "F.Fab")
		)
		(pad "1" smd custom
			(at 0 -0.4445)
			(size 0.1397 0.1397)
			(layers "F.Cu" "F.Mask" "F.Paste")
			(net "P3V3")
			(options
				(clearance outline)
				(anchor circle)
			)
			(primitives
				(gr_poly
					(pts
						(arc
							(start -0.1778 -0.2794)
							(mid -0.249642 -0.249642)
							(end -0.2794 -0.1778)
						)
						(arc
							(start -0.2794 0.1778)
							(mid -0.249642 0.249642)
							(end -0.1778 0.2794)
						)
						(arc
							(start 0.1778 0.2794)
							(mid 0.249642 0.249642)
							(end 0.2794 0.1778)
						)
						(arc
							(start 0.2794 -0.1778)
							(mid 0.249642 -0.249642)
							(end 0.1778 -0.2794)
						)
					)
					(width 0)
					(fill yes)
				)
			)
		)
		(pad "2" smd custom
			(at 0 0.4445)
			(size 0.1397 0.1397)
			(layers "F.Cu" "F.Mask" "F.Paste")
			(net "DUALPORTEN#7")
			(options
				(clearance outline)
				(anchor circle)
			)
			(primitives
				(gr_poly
					(pts
						(arc
							(start -0.1778 -0.2794)
							(mid -0.249642 -0.249642)
							(end -0.2794 -0.1778)
						)
						(arc
							(start -0.2794 0.1778)
							(mid -0.249642 0.249642)
							(end -0.1778 0.2794)
						)
						(arc
							(start 0.1778 0.2794)
							(mid 0.249642 0.249642)
							(end 0.2794 0.1778)
						)
						(arc
							(start 0.2794 -0.1778)
							(mid 0.249642 -0.249642)
							(end 0.1778 -0.2794)
						)
					)
					(width 0)
					(fill yes)
				)
			)
		)
	)
	(footprint ""
		(layer "F.Cu")
		(at 215.9 -94.9706 -90)
		(property "Reference" "Q46"
			(at 0 0 270)
			(layer "F.SilkS")
			(hide yes)
			(effects
				(font
					(size 1.27 1.27)
				)
			)
		)
		(property "Value" "2N7002A-7-GP"
			(at 0.127 -8.9662 270)
			(unlocked yes)
			(layer "F.Fab")
			(hide yes)
			(effects
				(font
					(size 1.016 1.016)
					(thickness 0.1524)
				)
			)
		)
		(property "Device Type" "SOT23DGS2D4H48"
			(at 0.127 -10.4902 270)
			(unlocked yes)
			(layer "F.Fab")
			(hide yes)
			(effects
				(font
					(size 1.016 1.016)
					(thickness 0.1524)
				)
			)
		)
		(duplicate_pad_numbers_are_jumpers no)
		(fp_line
			(start -1.651 1.778)
			(end 1.651 1.778)
			(stroke
				(width 0.1524)
				(type default)
			)
			(layer "F.SilkS")
		)
		(fp_line
			(start 1.651 1.778)
			(end 1.651 -1.778)
			(stroke
				(width 0.1524)
				(type default)
			)
			(layer "F.SilkS")
		)
		(fp_line
			(start -1.651 -1.778)
			(end -1.651 1.778)
			(stroke
				(width 0.1524)
				(type default)
			)
			(layer "F.SilkS")
		)
		(fp_line
			(start 1.651 -1.778)
			(end -1.651 -1.778)
			(stroke
				(width 0.1524)
				(type default)
			)
			(layer "F.SilkS")
		)
		(fp_poly
			(pts
				(xy -1.778 1.8796) (xy -1.778 -1.8796) (xy 1.778 -1.8796) (xy 1.778 1.8796)
			)
			(stroke
				(width 0)
				(type default)
			)
			(fill no)
			(layer "F.CrtYd")
		)
		(fp_poly
			(pts
				(xy -1.778 1.8796) (xy -1.778 -1.8796) (xy 1.778 -1.8796) (xy 1.778 1.8796)
			)
			(stroke
				(width 0)
				(type default)
			)
			(fill no)
			(layer "F.Fab")
		)
		(pad "D" smd custom
			(at 0 -0.9525 270)
			(size 0.1905 0.1905)
			(layers "F.Cu" "F.Mask" "F.Paste")
			(net "P12V_MOST4_GATE_D")
			(options
				(clearance outline)
				(anchor circle)
			)
			(primitives
				(gr_poly
					(pts
						(arc
							(start -0.1778 0.5715)
							(mid -0.321484 0.511984)
							(end -0.381 0.3683)
						)
						(arc
							(start -0.381 -0.3683)
							(mid -0.321484 -0.511984)
							(end -0.1778 -0.5715)
						)
						(arc
							(start 0.1778 -0.5715)
							(mid 0.321484 -0.511984)
							(end 0.381 -0.3683)
						)
						(arc
							(start 0.381 0.3683)
							(mid 0.321484 0.511984)
							(end 0.1778 0.5715)
						)
					)
					(width 0)
					(fill yes)
				)
			)
		)
		(pad "G" smd custom
			(at -0.98425 0.9525 270)
			(size 0.1905 0.1905)
			(layers "F.Cu" "F.Mask" "F.Paste")
			(net "P12V_MOST4_GATE")
			(options
				(clearance outline)
				(anchor circle)
			)
			(primitives
				(gr_poly
					(pts
						(arc
							(start -0.1778 0.5715)
							(mid -0.321484 0.511984)
							(end -0.381 0.3683)
						)
						(arc
							(start -0.381 -0.3683)
							(mid -0.321484 -0.511984)
							(end -0.1778 -0.5715)
						)
						(arc
							(start 0.1778 -0.5715)
							(mid 0.321484 -0.511984)
							(end 0.381 -0.3683)
						)
						(arc
							(start 0.381 0.3683)
							(mid 0.321484 0.511984)
							(end 0.1778 0.5715)
						)
					)
					(width 0)
					(fill yes)
				)
			)
		)
		(pad "S" smd custom
			(at 0.98425 0.9525 270)
			(size 0.1905 0.1905)
			(layers "F.Cu" "F.Mask" "F.Paste")
			(net "GND")
			(options
				(clearance outline)
				(anchor circle)
			)
			(primitives
				(gr_poly
					(pts
						(arc
							(start -0.1778 0.5715)
							(mid -0.321484 0.511984)
							(end -0.381 0.3683)
						)
						(arc
							(start -0.381 -0.3683)
							(mid -0.321484 -0.511984)
							(end -0.1778 -0.5715)
						)
						(arc
							(start 0.1778 -0.5715)
							(mid 0.321484 -0.511984)
							(end 0.381 -0.3683)
						)
						(arc
							(start 0.381 0.3683)
							(mid 0.321484 0.511984)
							(end 0.1778 0.5715)
						)
					)
					(width 0)
					(fill yes)
				)
			)
		)
	)
	(footprint ""
		(layer "F.Cu")
		(at 84.074 -144.92732 -90)
		(property "Reference" "R371"
			(at 0 0 270)
			(layer "F.SilkS")
			(hide yes)
			(effects
				(font
					(size 1.27 1.27)
				)
			)
		)
		(property "Value" "4K7R2J-2-GP"
			(at 0.064008 -3.993896 270)
			(unlocked yes)
			(layer "F.Fab")
			(hide yes)
			(effects
				(font
					(size 1.016 1.016)
					(thickness 0.1524)
				)
			)
		)
		(property "Device Type" "R402H16"
			(at 0.064008 -5.517896 270)
			(unlocked yes)
			(layer "F.Fab")
			(hide yes)
			(effects
				(font
					(size 1.016 1.016)
					(thickness 0.1524)
				)
			)
		)
		(duplicate_pad_numbers_are_jumpers no)
		(fp_line
			(start -0.508 -0.9398)
			(end -0.508 0.9398)
			(stroke
				(width 0.1524)
				(type default)
			)
			(layer "F.SilkS")
		)
		(fp_line
			(start 0.508 -0.9398)
			(end -0.508 -0.9398)
			(stroke
				(width 0.1524)
				(type default)
			)
			(layer "F.SilkS")
		)
		(fp_rect
			(start -0.508 0.9398)
			(end 0.508 -0.9398)
			(stroke
				(width 0)
				(type default)
			)
			(fill no)
			(layer "F.CrtYd")
		)
		(fp_rect
			(start -0.508 0.9398)
			(end 0.508 -0.9398)
			(stroke
				(width 0)
				(type default)
			)
			(fill no)
			(layer "F.Fab")
		)
		(pad "1" smd custom
			(at 0 -0.4445 270)
			(size 0.1397 0.1397)
			(layers "F.Cu" "F.Mask" "F.Paste")
			(net "P3V3")
			(options
				(clearance outline)
				(anchor circle)
			)
			(primitives
				(gr_poly
					(pts
						(arc
							(start -0.1778 -0.2794)
							(mid -0.249642 -0.249642)
							(end -0.2794 -0.1778)
						)
						(arc
							(start -0.2794 0.1778)
							(mid -0.249642 0.249642)
							(end -0.1778 0.2794)
						)
						(arc
							(start 0.1778 0.2794)
							(mid 0.249642 0.249642)
							(end 0.2794 0.1778)
						)
						(arc
							(start 0.2794 -0.1778)
							(mid 0.249642 -0.249642)
							(end 0.1778 -0.2794)
						)
					)
					(width 0)
					(fill yes)
				)
			)
		)
		(pad "2" smd custom
			(at 0 0.4445 270)
			(size 0.1397 0.1397)
			(layers "F.Cu" "F.Mask" "F.Paste")
			(net "BMC_I2C_SCL_BUF_8")
			(options
				(clearance outline)
				(anchor circle)
			)
			(primitives
				(gr_poly
					(pts
						(arc
							(start -0.1778 -0.2794)
							(mid -0.249642 -0.249642)
							(end -0.2794 -0.1778)
						)
						(arc
							(start -0.2794 0.1778)
							(mid -0.249642 0.249642)
							(end -0.1778 0.2794)
						)
						(arc
							(start 0.1778 0.2794)
							(mid 0.249642 0.249642)
							(end 0.2794 0.1778)
						)
						(arc
							(start 0.2794 -0.1778)
							(mid 0.249642 -0.249642)
							(end 0.1778 -0.2794)
						)
					)
					(width 0)
					(fill yes)
				)
			)
		)
	)
	(footprint ""
		(layer "F.Cu")
		(at 51.562 -136.398)
		(property "Reference" "R318"
			(at 0 0 0)
			(layer "F.SilkS")
			(hide yes)
			(effects
				(font
					(size 1.27 1.27)
				)
			)
		)
		(property "Value" "4K7R2F-GP"
			(at 0.064008 -3.993896 0)
			(unlocked yes)
			(layer "F.Fab")
			(hide yes)
			(effects
				(font
					(size 1.016 1.016)
					(thickness 0.1524)
				)
			)
		)
		(property "Device Type" "R402H16"
			(at 0.064008 -5.517896 0)
			(unlocked yes)
			(layer "F.Fab")
			(hide yes)
			(effects
				(font
					(size 1.016 1.016)
					(thickness 0.1524)
				)
			)
		)
		(duplicate_pad_numbers_are_jumpers no)
		(fp_line
			(start -0.508 -0.9398)
			(end -0.508 0.9398)
			(stroke
				(width 0.1524)
				(type default)
			)
			(layer "F.SilkS")
		)
		(fp_line
			(start 0.508 -0.9398)
			(end -0.508 -0.9398)
			(stroke
				(width 0.1524)
				(type default)
			)
			(layer "F.SilkS")
		)
		(fp_rect
			(start -0.508 0.9398)
			(end 0.508 -0.9398)
			(stroke
				(width 0)
				(type default)
			)
			(fill no)
			(layer "F.CrtYd")
		)
		(fp_rect
			(start -0.508 0.9398)
			(end 0.508 -0.9398)
			(stroke
				(width 0)
				(type default)
			)
			(fill no)
			(layer "F.Fab")
		)
		(pad "1" smd custom
			(at 0 -0.4445)
			(size 0.1397 0.1397)
			(layers "F.Cu" "F.Mask" "F.Paste")
			(net "P3V3")
			(options
				(clearance outline)
				(anchor circle)
			)
			(primitives
				(gr_poly
					(pts
						(arc
							(start -0.1778 -0.2794)
							(mid -0.249642 -0.249642)
							(end -0.2794 -0.1778)
						)
						(arc
							(start -0.2794 0.1778)
							(mid -0.249642 0.249642)
							(end -0.1778 0.2794)
						)
						(arc
							(start 0.1778 0.2794)
							(mid 0.249642 0.249642)
							(end 0.2794 0.1778)
						)
						(arc
							(start 0.2794 -0.1778)
							(mid 0.249642 -0.249642)
							(end 0.1778 -0.2794)
						)
					)
					(width 0)
					(fill yes)
				)
			)
		)
		(pad "2" smd custom
			(at 0 0.4445)
			(size 0.1397 0.1397)
			(layers "F.Cu" "F.Mask" "F.Paste")
			(net "I2C_B_TMP1_A1")
			(options
				(clearance outline)
				(anchor circle)
			)
			(primitives
				(gr_poly
					(pts
						(arc
							(start -0.1778 -0.2794)
							(mid -0.249642 -0.249642)
							(end -0.2794 -0.1778)
						)
						(arc
							(start -0.2794 0.1778)
							(mid -0.249642 0.249642)
							(end -0.1778 0.2794)
						)
						(arc
							(start 0.1778 0.2794)
							(mid 0.249642 0.249642)
							(end 0.2794 0.1778)
						)
						(arc
							(start 0.2794 -0.1778)
							(mid 0.249642 -0.249642)
							(end 0.1778 -0.2794)
						)
					)
					(width 0)
					(fill yes)
				)
			)
		)
	)
	(footprint ""
		(layer "F.Cu")
		(at 30.51175 -101.91115 90)
		(property "Reference" "Q91"
			(at 0 0 90)
			(layer "F.SilkS")
			(hide yes)
			(effects
				(font
					(size 1.27 1.27)
				)
			)
		)
		(property "Value" "2N7002A-7-GP"
			(at 0.127 -8.9662 90)
			(unlocked yes)
			(layer "F.Fab")
			(hide yes)
			(effects
				(font
					(size 1.016 1.016)
					(thickness 0.1524)
				)
			)
		)
		(property "Device Type" "SOT23DGS2D4H48"
			(at 0.127 -10.4902 90)
			(unlocked yes)
			(layer "F.Fab")
			(hide yes)
			(effects
				(font
					(size 1.016 1.016)
					(thickness 0.1524)
				)
			)
		)
		(duplicate_pad_numbers_are_jumpers no)
		(fp_line
			(start 1.651 -1.778)
			(end -1.651 -1.778)
			(stroke
				(width 0.1524)
				(type default)
			)
			(layer "F.SilkS")
		)
		(fp_line
			(start -1.651 -1.778)
			(end -1.651 1.778)
			(stroke
				(width 0.1524)
				(type default)
			)
			(layer "F.SilkS")
		)
		(fp_line
			(start 1.651 1.778)
			(end 1.651 -1.778)
			(stroke
				(width 0.1524)
				(type default)
			)
			(layer "F.SilkS")
		)
		(fp_line
			(start -1.651 1.778)
			(end 1.651 1.778)
			(stroke
				(width 0.1524)
				(type default)
			)
			(layer "F.SilkS")
		)
		(fp_poly
			(pts
				(xy -1.778 1.8796) (xy -1.778 -1.8796) (xy 1.778 -1.8796) (xy 1.778 1.8796)
			)
			(stroke
				(width 0)
				(type default)
			)
			(fill no)
			(layer "F.CrtYd")
		)
		(fp_poly
			(pts
				(xy -1.778 1.8796) (xy -1.778 -1.8796) (xy 1.778 -1.8796) (xy 1.778 1.8796)
			)
			(stroke
				(width 0)
				(type default)
			)
			(fill no)
			(layer "F.Fab")
		)
		(pad "D" smd custom
			(at 0 -0.9525 90)
			(size 0.1905 0.1905)
			(layers "F.Cu" "F.Mask" "F.Paste")
			(net "P12V_MOST13_GATE_D")
			(options
				(clearance outline)
				(anchor circle)
			)
			(primitives
				(gr_poly
					(pts
						(arc
							(start -0.1778 0.5715)
							(mid -0.321484 0.511984)
							(end -0.381 0.3683)
						)
						(arc
							(start -0.381 -0.3683)
							(mid -0.321484 -0.511984)
							(end -0.1778 -0.5715)
						)
						(arc
							(start 0.1778 -0.5715)
							(mid 0.321484 -0.511984)
							(end 0.381 -0.3683)
						)
						(arc
							(start 0.381 0.3683)
							(mid 0.321484 0.511984)
							(end 0.1778 0.5715)
						)
					)
					(width 0)
					(fill yes)
				)
			)
		)
		(pad "G" smd custom
			(at -0.98425 0.9525 90)
			(size 0.1905 0.1905)
			(layers "F.Cu" "F.Mask" "F.Paste")
			(net "P12V_MOST13_GATE")
			(options
				(clearance outline)
				(anchor circle)
			)
			(primitives
				(gr_poly
					(pts
						(arc
							(start -0.1778 0.5715)
							(mid -0.321484 0.511984)
							(end -0.381 0.3683)
						)
						(arc
							(start -0.381 -0.3683)
							(mid -0.321484 -0.511984)
							(end -0.1778 -0.5715)
						)
						(arc
							(start 0.1778 -0.5715)
							(mid 0.321484 -0.511984)
							(end 0.381 -0.3683)
						)
						(arc
							(start 0.381 0.3683)
							(mid 0.321484 0.511984)
							(end 0.1778 0.5715)
						)
					)
					(width 0)
					(fill yes)
				)
			)
		)
		(pad "S" smd custom
			(at 0.98425 0.9525 90)
			(size 0.1905 0.1905)
			(layers "F.Cu" "F.Mask" "F.Paste")
			(net "GND")
			(options
				(clearance outline)
				(anchor circle)
			)
			(primitives
				(gr_poly
					(pts
						(arc
							(start -0.1778 0.5715)
							(mid -0.321484 0.511984)
							(end -0.381 0.3683)
						)
						(arc
							(start -0.381 -0.3683)
							(mid -0.321484 -0.511984)
							(end -0.1778 -0.5715)
						)
						(arc
							(start 0.1778 -0.5715)
							(mid 0.321484 -0.511984)
							(end 0.381 -0.3683)
						)
						(arc
							(start 0.381 0.3683)
							(mid 0.321484 0.511984)
							(end 0.1778 0.5715)
						)
					)
					(width 0)
					(fill yes)
				)
			)
		)
	)
	(footprint ""
		(layer "F.Cu")
		(at 25.4 -30.988 180)
		(property "Reference" "PC1234"
			(at 0 0 180)
			(layer "F.SilkS")
			(hide yes)
			(effects
				(font
					(size 1.27 1.27)
				)
			)
		)
		(property "Value" "SCD1U25V3KX-GP"
			(at 0 -2.8194 180)
			(unlocked yes)
			(layer "F.Fab")
			(hide yes)
			(effects
				(font
					(size 1.016 1.016)
					(thickness 0.1524)
				)
			)
		)
		(property "Device Type" "C603H36"
			(at 0 -4.3434 180)
			(unlocked yes)
			(layer "F.Fab")
			(hide yes)
			(effects
				(font
					(size 1.016 1.016)
					(thickness 0.1524)
				)
			)
		)
		(duplicate_pad_numbers_are_jumpers no)
		(fp_line
			(start 0.508 0)
			(end -0.508 0)
			(stroke
				(width 0.2032)
				(type default)
			)
			(layer "F.SilkS")
		)
		(fp_rect
			(start -0.5842 1.3335)
			(end 0.5842 -1.3335)
			(stroke
				(width 0)
				(type default)
			)
			(fill no)
			(layer "F.CrtYd")
		)
		(fp_rect
			(start -0.5842 1.3335)
			(end 0.5842 -1.3335)
			(stroke
				(width 0)
				(type default)
			)
			(fill no)
			(layer "F.Fab")
		)
		(pad "1" smd custom
			(at 0 -0.762 180)
			(size 0.2159 0.2159)
			(layers "F.Cu" "F.Mask" "F.Paste")
			(net "P3V3")
			(options
				(clearance outline)
				(anchor circle)
			)
			(primitives
				(gr_poly
					(pts
						(arc
							(start -0.3302 -0.4318)
							(mid -0.402042 -0.402042)
							(end -0.4318 -0.3302)
						)
						(arc
							(start -0.4318 0.3302)
							(mid -0.402042 0.402042)
							(end -0.3302 0.4318)
						)
						(arc
							(start 0.3302 0.4318)
							(mid 0.402042 0.402042)
							(end 0.4318 0.3302)
						)
						(arc
							(start 0.4318 -0.3302)
							(mid 0.402042 -0.402042)
							(end 0.3302 -0.4318)
						)
					)
					(width 0)
					(fill yes)
				)
			)
		)
		(pad "2" smd custom
			(at 0 0.762 180)
			(size 0.2159 0.2159)
			(layers "F.Cu" "F.Mask" "F.Paste")
			(net "GND")
			(options
				(clearance outline)
				(anchor circle)
			)
			(primitives
				(gr_poly
					(pts
						(arc
							(start -0.3302 -0.4318)
							(mid -0.402042 -0.402042)
							(end -0.4318 -0.3302)
						)
						(arc
							(start -0.4318 0.3302)
							(mid -0.402042 0.402042)
							(end -0.3302 0.4318)
						)
						(arc
							(start 0.3302 0.4318)
							(mid 0.402042 0.402042)
							(end 0.4318 0.3302)
						)
						(arc
							(start 0.4318 -0.3302)
							(mid 0.402042 -0.402042)
							(end 0.3302 -0.4318)
						)
					)
					(width 0)
					(fill yes)
				)
			)
		)
	)
)
